# S9S_MB_2U (Grand Teton) — schematic netlist excerpt (pin names and nets, part order shuffled) for the footprints in the layout excerpt that follows; sources: Cadence DE-HDL packaged netlist, KiCad conversion of 03242023_DA0F0TMBIJ0_F0T_Motherboard_J_brd_V01_OCP.brd

PR4247  Q_RES  499 1% CHIP  pkg 0402LF  page 293 : A = PVCCINFAON_CPU1 ; B = GND
R3779  Q_RES  0 5% CHIP  pkg 0402LF  page 191 : A = RST_PCIE_PCH_DEV_PERST_E1S_R_N ; B = RST_PCIE_PCH_E1S_PERST_N

(kicad_pcb
	(version 20260206)
	(generator "pcbnew")
	(generator_version "10.0")
	(general
		(thickness 1.6)
		(legacy_teardrops no)
	)
	(paper "A4")
	(title_block
		(title "03242023_DA0F0TMBIJ0_F0T_Motherboard_J_brd_V01_OCP.brd")
		(comment 1 "Grand Teton / footprints 3802-3803 of 6105")
	)
	(layers
		(0 "F.Cu" signal "TOP")
		(4 "In1.Cu" signal "GND")
		(6 "In2.Cu" signal "IN1")
		(8 "In3.Cu" signal "GND1")
		(10 "In4.Cu" signal "IN2")
		(12 "In5.Cu" signal "GND2")
		(14 "In6.Cu" signal "IN3")
		(16 "In7.Cu" signal "GND3")
		(18 "In8.Cu" signal "VCC")
		(20 "In9.Cu" signal "VCC1")
		(22 "In10.Cu" signal "GND4")
		(24 "In11.Cu" signal "IN4")
		(26 "In12.Cu" signal "GND5")
		(28 "In13.Cu" signal "IN5")
		(30 "In14.Cu" signal "GND6")
		(32 "In15.Cu" signal "IN6")
		(34 "In16.Cu" signal "GND7")
		(2 "B.Cu" signal "BOTTOM")
		(9 "F.Adhes" user "F.Adhesive")
		(11 "B.Adhes" user "B.Adhesive")
		(13 "F.Paste" user "Package Geometry/Pastemask Top")
		(15 "B.Paste" user "Package Geometry/Pastemask Bottom")
		(5 "F.SilkS" user "Ref Des/Silkscreen Top")
		(7 "B.SilkS" user "Ref Des/Silkscreen Bottom")
		(1 "F.Mask" user "Board Geometry/Soldermask Top")
		(3 "B.Mask" user "Board Geometry/Soldermask Bottom")
		(17 "Dwgs.User" user "User.Drawings")
		(19 "Cmts.User" user "User.Comments")
		(21 "Eco1.User" user "User.Eco1")
		(23 "Eco2.User" user "User.Eco2")
		(25 "Edge.Cuts" user "Board Geometry/Outline")
		(27 "Margin" user)
		(31 "F.CrtYd" user "Package Geometry/Place Bound Top")
		(29 "B.CrtYd" user "Package Geometry/Place Bound Bottom")
		(35 "F.Fab" user "Ref Des/Assembly Top")
		(33 "B.Fab" user "Ref Des/Assembly Bottom")
	)
	(footprint ""
		(layer "F.Cu")
		(at 63.11011 -152.052528 180)
		(property "Reference" "PR4247"
			(at 0 0 180)
			(layer "F.SilkS")
			(hide yes)
			(effects
				(font
					(size 1.27 1.27)
				)
			)
		)
		(property "Value" ""
			(at 0 0 180)
			(layer "F.Fab")
			(effects
				(font
					(size 1.27 1.27)
				)
			)
		)
		(duplicate_pad_numbers_are_jumpers no)
		(fp_line
			(start 0.7874 0.4064)
			(end -0.7874 0.4064)
			(stroke
				(width 0.1524)
				(type default)
			)
			(layer "F.SilkS")
		)
		(fp_line
			(start 0.7874 -0.4064)
			(end 0.7874 0.4064)
			(stroke
				(width 0.1524)
				(type default)
			)
			(layer "F.SilkS")
		)
		(fp_line
			(start -0.7874 0.4064)
			(end -0.7874 -0.4064)
			(stroke
				(width 0.1524)
				(type default)
			)
			(layer "F.SilkS")
		)
		(fp_line
			(start -0.7874 -0.4064)
			(end 0.7874 -0.4064)
			(stroke
				(width 0.1524)
				(type default)
			)
			(layer "F.SilkS")
		)
		(fp_line
			(start 0.67945 0.3048)
			(end 0.120396 0.3048)
			(stroke
				(width 0.1)
				(type default)
			)
			(layer "F.Fab")
		)
		(fp_line
			(start 0.67945 -0.3048)
			(end 0.67945 0.3048)
			(stroke
				(width 0.1)
				(type default)
			)
			(layer "F.Fab")
		)
		(fp_line
			(start 0.12065 -0.2794)
			(end 0.12065 -0.3048)
			(stroke
				(width 0.1)
				(type default)
			)
			(layer "F.Fab")
		)
		(fp_line
			(start 0.12065 -0.3048)
			(end 0.67945 -0.3048)
			(stroke
				(width 0.1)
				(type default)
			)
			(layer "F.Fab")
		)
		(fp_line
			(start 0.120396 0.3048)
			(end 0.120396 0.2794)
			(stroke
				(width 0.1)
				(type default)
			)
			(layer "F.Fab")
		)
		(fp_line
			(start 0.120396 0.2794)
			(end -0.12065 0.2794)
			(stroke
				(width 0.1)
				(type default)
			)
			(layer "F.Fab")
		)
		(fp_line
			(start -0.12065 0.3048)
			(end -0.67945 0.3048)
			(stroke
				(width 0.1)
				(type default)
			)
			(layer "F.Fab")
		)
		(fp_line
			(start -0.12065 0.2794)
			(end -0.12065 0.3048)
			(stroke
				(width 0.1)
				(type default)
			)
			(layer "F.Fab")
		)
		(fp_line
			(start -0.12065 -0.2794)
			(end 0.12065 -0.2794)
			(stroke
				(width 0.1)
				(type default)
			)
			(layer "F.Fab")
		)
		(fp_line
			(start -0.12065 -0.305054)
			(end -0.12065 -0.2794)
			(stroke
				(width 0.1)
				(type default)
			)
			(layer "F.Fab")
		)
		(fp_line
			(start -0.67945 0.3048)
			(end -0.67945 -0.305054)
			(stroke
				(width 0.1)
				(type default)
			)
			(layer "F.Fab")
		)
		(fp_line
			(start -0.67945 -0.305054)
			(end -0.12065 -0.305054)
			(stroke
				(width 0.1)
				(type default)
			)
			(layer "F.Fab")
		)
		(pad "1" smd circle
			(at -0.40005 0 180)
			(size 0 0)
			(layers "F.Cu" "F.Mask" "F.Paste")
			(net "PVCCINFAON_CPU1")
		)
		(pad "2" smd circle
			(at 0.40005 0 180)
			(size 0 0)
			(layers "F.Cu" "F.Mask" "F.Paste")
			(net "GND")
		)
	)
	(footprint ""
		(layer "F.Cu")
		(at 239.98809 -47.968408 180)
		(property "Reference" "R3779"
			(at 0 0 180)
			(layer "F.SilkS")
			(hide yes)
			(effects
				(font
					(size 1.27 1.27)
				)
			)
		)
		(property "Value" ""
			(at 0 0 180)
			(layer "F.Fab")
			(effects
				(font
					(size 1.27 1.27)
				)
			)
		)
		(duplicate_pad_numbers_are_jumpers no)
		(fp_line
			(start 0.7874 0.4064)
			(end -0.7874 0.4064)
			(stroke
				(width 0.1524)
				(type default)
			)
			(layer "F.SilkS")
		)
		(fp_line
			(start 0.7874 -0.4064)
			(end 0.7874 0.4064)
			(stroke
				(width 0.1524)
				(type default)
			)
			(layer "F.SilkS")
		)
		(fp_line
			(start -0.7874 0.4064)
			(end -0.7874 -0.4064)
			(stroke
				(width 0.1524)
				(type default)
			)
			(layer "F.SilkS")
		)
		(fp_line
			(start -0.7874 -0.4064)
			(end 0.7874 -0.4064)
			(stroke
				(width 0.1524)
				(type default)
			)
			(layer "F.SilkS")
		)
		(fp_line
			(start 0.67945 0.3048)
			(end 0.120396 0.3048)
			(stroke
				(width 0.1)
				(type default)
			)
			(layer "F.Fab")
		)
		(fp_line
			(start 0.67945 -0.3048)
			(end 0.67945 0.3048)
			(stroke
				(width 0.1)
				(type default)
			)
			(layer "F.Fab")
		)
		(fp_line
			(start 0.12065 -0.2794)
			(end 0.12065 -0.3048)
			(stroke
				(width 0.1)
				(type default)
			)
			(layer "F.Fab")
		)
		(fp_line
			(start 0.12065 -0.3048)
			(end 0.67945 -0.3048)
			(stroke
				(width 0.1)
				(type default)
			)
			(layer "F.Fab")
		)
		(fp_line
			(start 0.120396 0.3048)
			(end 0.120396 0.2794)
			(stroke
				(width 0.1)
				(type default)
			)
			(layer "F.Fab")
		)
		(fp_line
			(start 0.120396 0.2794)
			(end -0.12065 0.2794)
			(stroke
				(width 0.1)
				(type default)
			)
			(layer "F.Fab")
		)
		(fp_line
			(start -0.12065 0.3048)
			(end -0.67945 0.3048)
			(stroke
				(width 0.1)
				(type default)
			)
			(layer "F.Fab")
		)
		(fp_line
			(start -0.12065 0.2794)
			(end -0.12065 0.3048)
			(stroke
				(width 0.1)
				(type default)
			)
			(layer "F.Fab")
		)
		(fp_line
			(start -0.12065 -0.2794)
			(end 0.12065 -0.2794)
			(stroke
				(width 0.1)
				(type default)
			)
			(layer "F.Fab")
		)
		(fp_line
			(start -0.12065 -0.305054)
			(end -0.12065 -0.2794)
			(stroke
				(width 0.1)
				(type default)
			)
			(layer "F.Fab")
		)
		(fp_line
			(start -0.67945 0.3048)
			(end -0.67945 -0.305054)
			(stroke
				(width 0.1)
				(type default)
			)
			(layer "F.Fab")
		)
		(fp_line
			(start -0.67945 -0.305054)
			(end -0.12065 -0.305054)
			(stroke
				(width 0.1)
				(type default)
			)
			(layer "F.Fab")
		)
		(pad "1" smd circle
			(at -0.40005 0 180)
			(size 0 0)
			(layers "F.Cu" "F.Mask" "F.Paste")
			(net "RST_PCIE_PCH_DEV_PERST_E1S_R_N")
		)
		(pad "2" smd circle
			(at 0.40005 0 180)
			(size 0 0)
			(layers "F.Cu" "F.Mask" "F.Paste")
			(net "RST_PCIE_PCH_E1S_PERST_N")
		)
	)
)
